# BASEBOARD_FAB2 (Tioga Pass) — schematic netlist excerpt (pin names and nets, part order shuffled) for the footprints in the layout excerpt that follows; sources: Cadence DE-HDL packaged netlist, KiCad conversion of Wiwynn_Tioga_Pass_MB.brd

C2D46  CAP_A  22.0UF 4V 20% X6S  pkg 0603V  page 225 : A = PVDDQ_GHJ ; B = GND
C7F7  SC22U16V5MX-4-GP  20%  pkg SMD-BCG5  page 231 : \1\ = VR_FET_SW_P12V_STBY_PVPP_ABC ; \2\ = GND
C25W15  CAP_A  0.1UF 16V 10% X7R  pkg 0402V  page 151 : A = P2V5_AUX_BMC ; B = GND
C6A1  CAP  22UF 4V 20% X6S  pkg 0805LF  page 219 : A = PVDDQ_DEF ; B = GND

(kicad_pcb
	(version 20260206)
	(generator "pcbnew")
	(generator_version "10.0")
	(general
		(thickness 1.6)
		(legacy_teardrops no)
	)
	(paper "A4")
	(title_block
		(title "Wiwynn_Tioga_Pass_MB.brd")
		(comment 1 "Tioga Pass / footprints 275-278 of 4770")
	)
	(layers
		(0 "F.Cu" signal "TOP")
		(4 "In1.Cu" signal "L2GND")
		(6 "In2.Cu" signal "L3")
		(8 "In3.Cu" signal "L4GND")
		(10 "In4.Cu" signal "L5")
		(12 "In5.Cu" signal "L6GND")
		(14 "In6.Cu" signal "L7VCC")
		(16 "In7.Cu" signal "L8VCC")
		(18 "In8.Cu" signal "L9GND")
		(20 "In9.Cu" signal "L10")
		(22 "In10.Cu" signal "L11GND")
		(24 "In11.Cu" signal "L12")
		(26 "In12.Cu" signal "L13GND")
		(2 "B.Cu" signal "BOTTOM")
		(9 "F.Adhes" user "F.Adhesive")
		(11 "B.Adhes" user "B.Adhesive")
		(13 "F.Paste" user "Package Geometry/Pastemask Top")
		(15 "B.Paste" user "Package Geometry/Pastemask Bottom")
		(5 "F.SilkS" user "Ref Des/Silkscreen Top")
		(7 "B.SilkS" user "Ref Des/Silkscreen Bottom")
		(1 "F.Mask" user "Board Geometry/Soldermask Top")
		(3 "B.Mask" user "Board Geometry/Soldermask Bottom")
		(17 "Dwgs.User" user "User.Drawings")
		(19 "Cmts.User" user "User.Comments")
		(21 "Eco1.User" user "User.Eco1")
		(23 "Eco2.User" user "User.Eco2")
		(25 "Edge.Cuts" user "Board Geometry/Outline")
		(27 "Margin" user)
		(31 "F.CrtYd" user "Package Geometry/Place Bound Top")
		(29 "B.CrtYd" user "Package Geometry/Place Bound Bottom")
		(35 "F.Fab" user "Ref Des/Assembly Top")
		(33 "B.Fab" user "Ref Des/Assembly Bottom")
	)
	(footprint ""
		(layer "F.Cu")
		(at 104.645206 -68.365116 180)
		(property "Reference" "C2D46"
			(at 0 0 180)
			(layer "F.SilkS")
			(hide yes)
			(effects
				(font
					(size 1.27 1.27)
				)
			)
		)
		(property "Value" ""
			(at 0 0 180)
			(layer "F.Fab")
			(effects
				(font
					(size 1.27 1.27)
				)
			)
		)
		(duplicate_pad_numbers_are_jumpers no)
		(fp_poly
			(pts
				(xy -0.4953 -0.2032) (xy 0.4953 -0.2032) (xy 0.4953 1.6002) (xy -0.4953 1.6002)
			)
			(stroke
				(width 0)
				(type default)
			)
			(fill no)
			(layer "F.CrtYd")
		)
		(fp_line
			(start 0.4953 1.6002)
			(end -0.4953 1.6002)
			(stroke
				(width 0.1)
				(type default)
			)
			(layer "F.Fab")
		)
		(fp_line
			(start 0.4953 -0.2032)
			(end 0.4953 1.6002)
			(stroke
				(width 0.1)
				(type default)
			)
			(layer "F.Fab")
		)
		(fp_line
			(start -0.4953 1.6002)
			(end -0.4953 -0.2032)
			(stroke
				(width 0.1)
				(type default)
			)
			(layer "F.Fab")
		)
		(fp_line
			(start -0.4953 -0.2032)
			(end 0.4953 -0.2032)
			(stroke
				(width 0.1)
				(type default)
			)
			(layer "F.Fab")
		)
		(pad "1" smd rect
			(at 0 0 180)
			(size 0.762 0.889)
			(layers "F.Cu" "F.Mask" "F.Paste")
			(net "PVDDQ_GHJ")
		)
		(pad "2" smd rect
			(at 0 1.397 180)
			(size 0.762 0.889)
			(layers "F.Cu" "F.Mask" "F.Paste")
			(net "GND")
		)
		(zone
			(layer "F.Cu")
			(hatch none 0.5)
			(connect_pads
				(clearance 0)
			)
			(min_thickness 0.25)
			(keepout
				(tracks not_allowed)
				(vias allowed)
				(pads allowed)
				(copperpour not_allowed)
				(footprints allowed)
			)
			(placement
				(enabled no)
				(sheetname "")
			)
			(fill
				(thermal_gap 0.5)
				(thermal_bridge_width 0.5)
				(island_removal_mode 0)
			)
			(polygon
				(pts
					(xy 105.026206 -68.809616) (xy 104.264206 -68.809616) (xy 104.264206 -69.317616) (xy 105.026206 -69.317616)
				)
			)
		)
	)
	(footprint ""
		(layer "F.Cu")
		(at 446.73012 -24.47798)
		(property "Reference" "C25W15"
			(at -0.8382 -0.67818 0)
			(unlocked yes)
			(layer "F.SilkS")
			(effects
				(font
					(size 0.4064 0.254)
					(thickness 0.1524)
				)
				(justify left)
			)
		)
		(property "Value" ""
			(at 0 0 0)
			(layer "F.Fab")
			(effects
				(font
					(size 1.27 1.27)
				)
			)
		)
		(duplicate_pad_numbers_are_jumpers no)
		(fp_poly
			(pts
				(xy 0.3048 -0.1016) (xy 0.3048 0.9906) (xy -0.3048 0.9906) (xy -0.3048 -0.1016)
			)
			(stroke
				(width 0)
				(type default)
			)
			(fill no)
			(layer "F.CrtYd")
		)
		(fp_line
			(start -0.3048 -0.1016)
			(end -0.3048 0.9906)
			(stroke
				(width 0.1)
				(type default)
			)
			(layer "F.Fab")
		)
		(fp_line
			(start -0.3048 0.9906)
			(end 0.3048 0.9906)
			(stroke
				(width 0.1)
				(type default)
			)
			(layer "F.Fab")
		)
		(fp_line
			(start 0.3048 -0.1016)
			(end -0.3048 -0.1016)
			(stroke
				(width 0.1)
				(type default)
			)
			(layer "F.Fab")
		)
		(fp_line
			(start 0.3048 0.9906)
			(end 0.3048 -0.1016)
			(stroke
				(width 0.1)
				(type default)
			)
			(layer "F.Fab")
		)
		(pad "1" smd rect
			(at 0 0)
			(size 0.508 0.508)
			(layers "F.Cu" "F.Mask" "F.Paste")
			(net "P2V5_AUX_BMC")
		)
		(pad "2" smd rect
			(at 0 0.889)
			(size 0.508 0.508)
			(layers "F.Cu" "F.Mask" "F.Paste")
			(net "GND")
		)
		(zone
			(layer "F.Cu")
			(hatch none 0.5)
			(connect_pads
				(clearance 0)
			)
			(min_thickness 0.25)
			(keepout
				(tracks allowed)
				(vias not_allowed)
				(pads allowed)
				(copperpour not_allowed)
				(footprints allowed)
			)
			(placement
				(enabled no)
				(sheetname "")
			)
			(fill
				(thermal_gap 0.5)
				(thermal_bridge_width 0.5)
				(island_removal_mode 0)
			)
			(polygon
				(pts
					(xy 446.47612 -24.22398) (xy 446.98412 -24.22398) (xy 446.98412 -23.84298) (xy 446.47612 -23.84298)
				)
			)
		)
		(zone
			(layer "F.Cu")
			(hatch none 0.5)
			(connect_pads
				(clearance 0)
			)
			(min_thickness 0.25)
			(keepout
				(tracks not_allowed)
				(vias allowed)
				(pads allowed)
				(copperpour not_allowed)
				(footprints allowed)
			)
			(placement
				(enabled no)
				(sheetname "")
			)
			(fill
				(thermal_gap 0.5)
				(thermal_bridge_width 0.5)
				(island_removal_mode 0)
			)
			(polygon
				(pts
					(xy 446.47612 -23.84298) (xy 446.98412 -23.84298) (xy 446.98412 -24.22398) (xy 446.47612 -24.22398)
				)
			)
		)
	)
	(footprint ""
		(layer "F.Cu")
		(at 330.962 -153.543)
		(property "Reference" "C6A1"
			(at 0 0 0)
			(layer "F.SilkS")
			(hide yes)
			(effects
				(font
					(size 1.27 1.27)
				)
			)
		)
		(property "Value" ""
			(at 0 0 0)
			(layer "F.Fab")
			(effects
				(font
					(size 1.27 1.27)
				)
			)
		)
		(duplicate_pad_numbers_are_jumpers no)
		(fp_rect
			(start -0.7239 1.9939)
			(end 0.7239 -0.2159)
			(stroke
				(width 0)
				(type default)
			)
			(fill no)
			(layer "F.CrtYd")
		)
		(fp_line
			(start -0.7239 -0.2159)
			(end -0.7239 1.9939)
			(stroke
				(width 0.1)
				(type default)
			)
			(layer "F.Fab")
		)
		(fp_line
			(start -0.7239 1.9939)
			(end 0.7239 1.9939)
			(stroke
				(width 0.1)
				(type default)
			)
			(layer "F.Fab")
		)
		(fp_line
			(start 0.7239 -0.2159)
			(end -0.7239 -0.2159)
			(stroke
				(width 0.1)
				(type default)
			)
			(layer "F.Fab")
		)
		(fp_line
			(start 0.7239 1.9939)
			(end 0.7239 -0.2159)
			(stroke
				(width 0.1)
				(type default)
			)
			(layer "F.Fab")
		)
		(pad "1" smd rect
			(at 0 0)
			(size 1.27 1.016)
			(layers "F.Cu" "F.Mask" "F.Paste")
			(net "PVDDQ_DEF")
		)
		(pad "2" smd rect
			(at 0 1.778)
			(size 1.27 1.016)
			(layers "F.Cu" "F.Mask" "F.Paste")
			(net "GND")
		)
		(zone
			(layer "F.Cu")
			(hatch none 0.5)
			(connect_pads
				(clearance 0)
			)
			(min_thickness 0.25)
			(keepout
				(tracks not_allowed)
				(vias allowed)
				(pads allowed)
				(copperpour not_allowed)
				(footprints allowed)
			)
			(placement
				(enabled no)
				(sheetname "")
			)
			(fill
				(thermal_gap 0.5)
				(thermal_bridge_width 0.5)
				(island_removal_mode 0)
			)
			(polygon
				(pts
					(xy 330.327 -152.273) (xy 331.597 -152.273) (xy 331.597 -153.035) (xy 330.327 -153.035)
				)
			)
		)
	)
	(footprint ""
		(layer "F.Cu")
		(at 352.24593 -25.676606 90)
		(property "Reference" "C7F7"
			(at 0 0 90)
			(layer "F.SilkS")
			(hide yes)
			(effects
				(font
					(size 1.27 1.27)
				)
			)
		)
		(property "Value" "*"
			(at -0.0762 -6.2357 90)
			(unlocked yes)
			(layer "F.Fab")
			(hide yes)
			(effects
				(font
					(size 1.27 1.016)
					(thickness 0.1524)
				)
			)
		)
		(property "Device Type" "SC22U16V5MX-4-GP_SMD-BCG5-SC22A"
			(at -0.0762 -8.2677 90)
			(unlocked yes)
			(layer "F.Fab")
			(hide yes)
			(effects
				(font
					(size 1.27 1.016)
					(thickness 0.1524)
				)
			)
		)
		(duplicate_pad_numbers_are_jumpers no)
		(fp_line
			(start 0.635 0)
			(end -0.635 0)
			(stroke
				(width 0.508)
				(type default)
			)
			(layer "F.SilkS")
		)
		(fp_rect
			(start -0.9652 1.778)
			(end 0.9652 -1.778)
			(stroke
				(width 0)
				(type default)
			)
			(fill no)
			(layer "F.CrtYd")
		)
		(fp_poly
			(pts
				(xy -0.9652 -1.778) (xy 0.9652 -1.778) (xy 0.9652 1.778) (xy -0.9652 1.778)
			)
			(stroke
				(width 0)
				(type default)
			)
			(fill no)
			(layer "F.Fab")
		)
		(pad "1" smd rect
			(at 0 -0.9652 90)
			(size 1.397 1.143)
			(layers "F.Cu" "F.Mask" "F.Paste")
			(net "VR_FET_SW_P12V_STBY_PVPP_ABC")
		)
		(pad "2" smd rect
			(at 0 0.9652 90)
			(size 1.397 1.143)
			(layers "F.Cu" "F.Mask" "F.Paste")
			(net "GND")
		)
	)
)
